# T6G (Grand Teton) — schematic netlist excerpt (pin names and nets, part order shuffled) for the footprints in the layout excerpt that follows; sources: Cadence DE-HDL packaged netlist, KiCad conversion of 04192023_DAF0TMB3IC0_F0TG_MB_C_brd_V02_OCP.brd

C1235  Q_CAP  0.1UF 25V 10% X7R  pkg 0402  page 131 : A = P12V_OCP_SFF_R ; B = GND
PR6521  Q_RES  0 5% CHIP  pkg 0402LF  page 361 : A = P3V3_AUX ; B = P1V8_RETIMER_CPU1_VCC

(kicad_pcb
	(version 20260206)
	(generator "pcbnew")
	(generator_version "10.0")
	(general
		(thickness 1.6)
		(legacy_teardrops no)
	)
	(paper "A4")
	(title_block
		(title "04192023_DAF0TMB3IC0_F0TG_MB_C_brd_V02_OCP.brd")
		(comment 1 "Grand Teton / footprints 6285-6286 of 8354")
	)
	(layers
		(0 "F.Cu" signal "TOP")
		(4 "In1.Cu" signal "GND")
		(6 "In2.Cu" signal "IN1")
		(8 "In3.Cu" signal "GND1")
		(10 "In4.Cu" signal "IN2")
		(12 "In5.Cu" signal "GND2")
		(14 "In6.Cu" signal "IN3")
		(16 "In7.Cu" signal "GND3")
		(18 "In8.Cu" signal "VCC")
		(20 "In9.Cu" signal "VCC1")
		(22 "In10.Cu" signal "GND4")
		(24 "In11.Cu" signal "IN4")
		(26 "In12.Cu" signal "GND5")
		(28 "In13.Cu" signal "IN5")
		(30 "In14.Cu" signal "GND6")
		(32 "In15.Cu" signal "IN6")
		(34 "In16.Cu" signal "GND7")
		(2 "B.Cu" signal "BOTTOM")
		(9 "F.Adhes" user "F.Adhesive")
		(11 "B.Adhes" user "B.Adhesive")
		(13 "F.Paste" user "Package Geometry/Pastemask Top")
		(15 "B.Paste" user "Package Geometry/Pastemask Bottom")
		(5 "F.SilkS" user "Ref Des/Silkscreen Top")
		(7 "B.SilkS" user "Ref Des/Silkscreen Bottom")
		(1 "F.Mask" user "Board Geometry/Soldermask Top")
		(3 "B.Mask" user "Board Geometry/Soldermask Bottom")
		(17 "Dwgs.User" user "User.Drawings")
		(19 "Cmts.User" user "User.Comments")
		(21 "Eco1.User" user "User.Eco1")
		(23 "Eco2.User" user "User.Eco2")
		(25 "Edge.Cuts" user "Board Geometry/Outline")
		(27 "Margin" user)
		(31 "F.CrtYd" user "Package Geometry/Place Bound Top")
		(29 "B.CrtYd" user "Package Geometry/Place Bound Bottom")
		(35 "F.Fab" user "Ref Des/Assembly Top")
		(33 "B.Fab" user "Ref Des/Assembly Bottom")
	)
	(footprint ""
		(layer "B.Cu")
		(at 229.993698 -289.533838 -90)
		(property "Reference" "PR6521"
			(at 0 0 90)
			(layer "B.SilkS")
			(hide yes)
			(effects
				(font
					(size 1.27 1.27)
				)
				(justify mirror)
			)
		)
		(property "Value" ""
			(at 0 0 90)
			(layer "B.Fab")
			(effects
				(font
					(size 1.27 1.27)
				)
				(justify mirror)
			)
		)
		(duplicate_pad_numbers_are_jumpers no)
		(fp_line
			(start -0.7874 0.4064)
			(end 0.7874 0.4064)
			(stroke
				(width 0.1524)
				(type default)
			)
			(layer "B.SilkS")
		)
		(fp_line
			(start 0.7874 0.4064)
			(end 0.7874 -0.4064)
			(stroke
				(width 0.1524)
				(type default)
			)
			(layer "B.SilkS")
		)
		(fp_line
			(start -0.7874 -0.4064)
			(end -0.7874 0.4064)
			(stroke
				(width 0.1524)
				(type default)
			)
			(layer "B.SilkS")
		)
		(fp_line
			(start 0.7874 -0.4064)
			(end -0.7874 -0.4064)
			(stroke
				(width 0.1524)
				(type default)
			)
			(layer "B.SilkS")
		)
		(fp_line
			(start -0.67945 0.3048)
			(end -0.120396 0.3048)
			(stroke
				(width 0.1)
				(type default)
			)
			(layer "B.Fab")
		)
		(fp_line
			(start -0.120396 0.3048)
			(end -0.120396 0.2794)
			(stroke
				(width 0.1)
				(type default)
			)
			(layer "B.Fab")
		)
		(fp_line
			(start 0.12065 0.3048)
			(end 0.67945 0.3048)
			(stroke
				(width 0.1)
				(type default)
			)
			(layer "B.Fab")
		)
		(fp_line
			(start 0.67945 0.3048)
			(end 0.67945 -0.305054)
			(stroke
				(width 0.1)
				(type default)
			)
			(layer "B.Fab")
		)
		(fp_line
			(start -0.120396 0.2794)
			(end 0.12065 0.2794)
			(stroke
				(width 0.1)
				(type default)
			)
			(layer "B.Fab")
		)
		(fp_line
			(start 0.12065 0.2794)
			(end 0.12065 0.3048)
			(stroke
				(width 0.1)
				(type default)
			)
			(layer "B.Fab")
		)
		(fp_line
			(start -0.12065 -0.2794)
			(end -0.12065 -0.3048)
			(stroke
				(width 0.1)
				(type default)
			)
			(layer "B.Fab")
		)
		(fp_line
			(start 0.12065 -0.2794)
			(end -0.12065 -0.2794)
			(stroke
				(width 0.1)
				(type default)
			)
			(layer "B.Fab")
		)
		(fp_line
			(start -0.67945 -0.3048)
			(end -0.67945 0.3048)
			(stroke
				(width 0.1)
				(type default)
			)
			(layer "B.Fab")
		)
		(fp_line
			(start -0.12065 -0.3048)
			(end -0.67945 -0.3048)
			(stroke
				(width 0.1)
				(type default)
			)
			(layer "B.Fab")
		)
		(fp_line
			(start 0.12065 -0.305054)
			(end 0.12065 -0.2794)
			(stroke
				(width 0.1)
				(type default)
			)
			(layer "B.Fab")
		)
		(fp_line
			(start 0.67945 -0.305054)
			(end 0.12065 -0.305054)
			(stroke
				(width 0.1)
				(type default)
			)
			(layer "B.Fab")
		)
		(pad "1" smd circle
			(at 0.40005 0 90)
			(size 0 0)
			(layers "B.Cu" "B.Mask" "B.Paste")
			(net "P3V3_AUX")
		)
		(pad "2" smd circle
			(at -0.40005 0 90)
			(size 0 0)
			(layers "B.Cu" "B.Mask" "B.Paste")
			(net "P1V8_RETIMER_CPU1_VCC")
		)
	)
	(footprint ""
		(layer "B.Cu")
		(at 440.40171 -13.627354)
		(property "Reference" "C1235"
			(at 0 0 0)
			(layer "B.SilkS")
			(hide yes)
			(effects
				(font
					(size 1.27 1.27)
				)
				(justify mirror)
			)
		)
		(property "Value" ""
			(at 0 0 0)
			(layer "B.Fab")
			(effects
				(font
					(size 1.27 1.27)
				)
				(justify mirror)
			)
		)
		(duplicate_pad_numbers_are_jumpers no)
		(fp_line
			(start -0.7874 -0.4064)
			(end -0.7874 0.4064)
			(stroke
				(width 0.1524)
				(type default)
			)
			(layer "B.SilkS")
		)
		(fp_line
			(start -0.7874 0.4064)
			(end 0.7874 0.4064)
			(stroke
				(width 0.1524)
				(type default)
			)
			(layer "B.SilkS")
		)
		(fp_line
			(start 0.7874 -0.4064)
			(end -0.7874 -0.4064)
			(stroke
				(width 0.1524)
				(type default)
			)
			(layer "B.SilkS")
		)
		(fp_line
			(start 0.7874 0.4064)
			(end 0.7874 -0.4064)
			(stroke
				(width 0.1524)
				(type default)
			)
			(layer "B.SilkS")
		)
		(fp_line
			(start -0.67945 -0.3048)
			(end -0.67945 0.3048)
			(stroke
				(width 0.1)
				(type default)
			)
			(layer "B.Fab")
		)
		(fp_line
			(start -0.67945 0.3048)
			(end -0.120396 0.3048)
			(stroke
				(width 0.1)
				(type default)
			)
			(layer "B.Fab")
		)
		(fp_line
			(start -0.12065 -0.3048)
			(end -0.67945 -0.3048)
			(stroke
				(width 0.1)
				(type default)
			)
			(layer "B.Fab")
		)
		(fp_line
			(start -0.12065 -0.2794)
			(end -0.12065 -0.3048)
			(stroke
				(width 0.1)
				(type default)
			)
			(layer "B.Fab")
		)
		(fp_line
			(start -0.120396 0.2794)
			(end 0.12065 0.2794)
			(stroke
				(width 0.1)
				(type default)
			)
			(layer "B.Fab")
		)
		(fp_line
			(start -0.120396 0.3048)
			(end -0.120396 0.2794)
			(stroke
				(width 0.1)
				(type default)
			)
			(layer "B.Fab")
		)
		(fp_line
			(start 0.12065 -0.305054)
			(end 0.12065 -0.2794)
			(stroke
				(width 0.1)
				(type default)
			)
			(layer "B.Fab")
		)
		(fp_line
			(start 0.12065 -0.2794)
			(end -0.12065 -0.2794)
			(stroke
				(width 0.1)
				(type default)
			)
			(layer "B.Fab")
		)
		(fp_line
			(start 0.12065 0.2794)
			(end 0.12065 0.3048)
			(stroke
				(width 0.1)
				(type default)
			)
			(layer "B.Fab")
		)
		(fp_line
			(start 0.12065 0.3048)
			(end 0.67945 0.3048)
			(stroke
				(width 0.1)
				(type default)
			)
			(layer "B.Fab")
		)
		(fp_line
			(start 0.67945 -0.305054)
			(end 0.12065 -0.305054)
			(stroke
				(width 0.1)
				(type default)
			)
			(layer "B.Fab")
		)
		(fp_line
			(start 0.67945 0.3048)
			(end 0.67945 -0.305054)
			(stroke
				(width 0.1)
				(type default)
			)
			(layer "B.Fab")
		)
		(pad "1" smd circle
			(at 0.40005 0 180)
			(size 0 0)
			(layers "B.Cu" "B.Mask" "B.Paste")
			(net "P12V_OCP_SFF_R")
		)
		(pad "2" smd circle
			(at -0.40005 0 180)
			(size 0 0)
			(layers "B.Cu" "B.Mask" "B.Paste")
			(net "GND")
		)
	)
)
